# BASEBOARD_FAB2 (Tioga Pass) — schematic netlist excerpt (pin names and nets, part order shuffled) for the footprints in the layout excerpt that follows; sources: Cadence DE-HDL packaged netlist, KiCad conversion of Wiwynn_Tioga_Pass_MB.brd

R1T32  RES  0 5.0% CHIP  pkg 0603  page 139 : A = P1V5_LAN ; B = P1V5_LAN_I210
C3P33  CAP  0.22UF 16V 10% X7R  pkg 0402  page 107 : A = P3E_CPU0_PE1_SS_TXN<5> ; B = P3E_CPU0_PE1_SS_C_TXN<5>
R7D15  RES  348 1% CHIP  pkg 0402  page 166 : A = PECI_PCH ; B = GND

(kicad_pcb
	(version 20260206)
	(generator "pcbnew")
	(generator_version "10.0")
	(general
		(thickness 1.6)
		(legacy_teardrops no)
	)
	(paper "A4")
	(title_block
		(title "Wiwynn_Tioga_Pass_MB.brd")
		(comment 1 "Tioga Pass / footprints 2873-2875 of 4770")
	)
	(layers
		(0 "F.Cu" signal "TOP")
		(4 "In1.Cu" signal "L2GND")
		(6 "In2.Cu" signal "L3")
		(8 "In3.Cu" signal "L4GND")
		(10 "In4.Cu" signal "L5")
		(12 "In5.Cu" signal "L6GND")
		(14 "In6.Cu" signal "L7VCC")
		(16 "In7.Cu" signal "L8VCC")
		(18 "In8.Cu" signal "L9GND")
		(20 "In9.Cu" signal "L10")
		(22 "In10.Cu" signal "L11GND")
		(24 "In11.Cu" signal "L12")
		(26 "In12.Cu" signal "L13GND")
		(2 "B.Cu" signal "BOTTOM")
		(9 "F.Adhes" user "F.Adhesive")
		(11 "B.Adhes" user "B.Adhesive")
		(13 "F.Paste" user "Package Geometry/Pastemask Top")
		(15 "B.Paste" user "Package Geometry/Pastemask Bottom")
		(5 "F.SilkS" user "Ref Des/Silkscreen Top")
		(7 "B.SilkS" user "Ref Des/Silkscreen Bottom")
		(1 "F.Mask" user "Board Geometry/Soldermask Top")
		(3 "B.Mask" user "Board Geometry/Soldermask Bottom")
		(17 "Dwgs.User" user "User.Drawings")
		(19 "Cmts.User" user "User.Comments")
		(21 "Eco1.User" user "User.Eco1")
		(23 "Eco2.User" user "User.Eco2")
		(25 "Edge.Cuts" user "Board Geometry/Outline")
		(27 "Margin" user)
		(31 "F.CrtYd" user "Package Geometry/Place Bound Top")
		(29 "B.CrtYd" user "Package Geometry/Place Bound Bottom")
		(35 "F.Fab" user "Ref Des/Assembly Top")
		(33 "B.Fab" user "Ref Des/Assembly Bottom")
	)
	(footprint ""
		(layer "B.Cu")
		(at 383.42824 -81.06918 90)
		(property "Reference" "R7D15"
			(at 0.8382 -0.67818 90)
			(unlocked yes)
			(layer "B.SilkS")
			(effects
				(font
					(size 0.4064 0.254)
					(thickness 0.1524)
				)
				(justify left mirror)
			)
		)
		(property "Value" ""
			(at 0 0 90)
			(layer "B.Fab")
			(effects
				(font
					(size 1.27 1.27)
				)
				(justify mirror)
			)
		)
		(duplicate_pad_numbers_are_jumpers no)
		(fp_poly
			(pts
				(xy 0.2794 -0.1016) (xy -0.2794 -0.1016) (xy -0.2794 0.9906) (xy 0.2794 0.9906)
			)
			(stroke
				(width 0)
				(type default)
			)
			(fill no)
			(layer "B.CrtYd")
		)
		(fp_line
			(start 0.2794 -0.1016)
			(end 0.2794 0.9906)
			(stroke
				(width 0.1)
				(type default)
			)
			(layer "B.Fab")
		)
		(fp_line
			(start -0.2794 -0.1016)
			(end 0.2794 -0.1016)
			(stroke
				(width 0.1)
				(type default)
			)
			(layer "B.Fab")
		)
		(fp_line
			(start 0.2794 0.9906)
			(end -0.2794 0.9906)
			(stroke
				(width 0.1)
				(type default)
			)
			(layer "B.Fab")
		)
		(fp_line
			(start -0.2794 0.9906)
			(end -0.2794 -0.1016)
			(stroke
				(width 0.1)
				(type default)
			)
			(layer "B.Fab")
		)
		(pad "1" smd rect
			(at 0 0 270)
			(size 0.508 0.508)
			(layers "B.Cu" "B.Mask" "B.Paste")
			(net "PECI_PCH")
		)
		(pad "2" smd rect
			(at 0 0.889 270)
			(size 0.508 0.508)
			(layers "B.Cu" "B.Mask" "B.Paste")
			(net "GND")
		)
		(zone
			(layer "B.Cu")
			(hatch none 0.5)
			(connect_pads
				(clearance 0)
			)
			(min_thickness 0.25)
			(keepout
				(tracks allowed)
				(vias not_allowed)
				(pads allowed)
				(copperpour not_allowed)
				(footprints allowed)
			)
			(placement
				(enabled no)
				(sheetname "")
			)
			(fill
				(thermal_gap 0.5)
				(thermal_bridge_width 0.5)
				(island_removal_mode 0)
			)
			(polygon
				(pts
					(xy 383.68224 -81.32318) (xy 383.68224 -80.81518) (xy 384.06324 -80.81518) (xy 384.06324 -81.32318)
				)
			)
		)
		(zone
			(layer "B.Cu")
			(hatch none 0.5)
			(connect_pads
				(clearance 0)
			)
			(min_thickness 0.25)
			(keepout
				(tracks not_allowed)
				(vias allowed)
				(pads allowed)
				(copperpour not_allowed)
				(footprints allowed)
			)
			(placement
				(enabled no)
				(sheetname "")
			)
			(fill
				(thermal_gap 0.5)
				(thermal_bridge_width 0.5)
				(island_removal_mode 0)
			)
			(polygon
				(pts
					(xy 384.06324 -81.32318) (xy 384.06324 -80.81518) (xy 383.68224 -80.81518) (xy 383.68224 -81.32318)
				)
			)
		)
	)
	(footprint ""
		(layer "B.Cu")
		(at 354.36429 -77.915516)
		(property "Reference" "C3P33"
			(at 0 0 0)
			(layer "B.SilkS")
			(hide yes)
			(effects
				(font
					(size 1.27 1.27)
				)
				(justify mirror)
			)
		)
		(property "Value" ""
			(at 0 0 0)
			(layer "B.Fab")
			(effects
				(font
					(size 1.27 1.27)
				)
				(justify mirror)
			)
		)
		(duplicate_pad_numbers_are_jumpers no)
		(fp_poly
			(pts
				(xy -0.3048 -0.1016) (xy -0.3048 0.9906) (xy 0.3048 0.9906) (xy 0.3048 -0.1016)
			)
			(stroke
				(width 0)
				(type default)
			)
			(fill no)
			(layer "B.CrtYd")
		)
		(fp_line
			(start -0.3048 -0.1016)
			(end 0.3048 -0.1016)
			(stroke
				(width 0.1)
				(type default)
			)
			(layer "B.Fab")
		)
		(fp_line
			(start -0.3048 0.9906)
			(end -0.3048 -0.1016)
			(stroke
				(width 0.1)
				(type default)
			)
			(layer "B.Fab")
		)
		(fp_line
			(start 0.3048 -0.1016)
			(end 0.3048 0.9906)
			(stroke
				(width 0.1)
				(type default)
			)
			(layer "B.Fab")
		)
		(fp_line
			(start 0.3048 0.9906)
			(end -0.3048 0.9906)
			(stroke
				(width 0.1)
				(type default)
			)
			(layer "B.Fab")
		)
		(pad "1" smd rect
			(at 0 0 180)
			(size 0.508 0.508)
			(layers "B.Cu" "B.Mask" "B.Paste")
			(net "P3E_CPU0_PE1_SS_TXN<5>")
		)
		(pad "2" smd rect
			(at 0 0.889 180)
			(size 0.508 0.508)
			(layers "B.Cu" "B.Mask" "B.Paste")
			(net "P3E_CPU0_PE1_SS_C_TXN<5>")
		)
		(zone
			(layer "B.Cu")
			(hatch none 0.5)
			(connect_pads
				(clearance 0)
			)
			(min_thickness 0.25)
			(keepout
				(tracks allowed)
				(vias not_allowed)
				(pads allowed)
				(copperpour not_allowed)
				(footprints allowed)
			)
			(placement
				(enabled no)
				(sheetname "")
			)
			(fill
				(thermal_gap 0.5)
				(thermal_bridge_width 0.5)
				(island_removal_mode 0)
			)
			(polygon
				(pts
					(xy 354.61829 -77.661516) (xy 354.11029 -77.661516) (xy 354.11029 -77.280516) (xy 354.61829 -77.280516)
				)
			)
		)
		(zone
			(layer "B.Cu")
			(hatch none 0.5)
			(connect_pads
				(clearance 0)
			)
			(min_thickness 0.25)
			(keepout
				(tracks not_allowed)
				(vias allowed)
				(pads allowed)
				(copperpour not_allowed)
				(footprints allowed)
			)
			(placement
				(enabled no)
				(sheetname "")
			)
			(fill
				(thermal_gap 0.5)
				(thermal_bridge_width 0.5)
				(island_removal_mode 0)
			)
			(polygon
				(pts
					(xy 354.61829 -77.280516) (xy 354.11029 -77.280516) (xy 354.11029 -77.661516) (xy 354.61829 -77.661516)
				)
			)
		)
	)
	(footprint ""
		(layer "B.Cu")
		(at 482.9556 -38.4429 180)
		(property "Reference" "R1T32"
			(at 0 0 0)
			(layer "B.SilkS")
			(hide yes)
			(effects
				(font
					(size 1.27 1.27)
				)
				(justify mirror)
			)
		)
		(property "Value" ""
			(at 0 0 0)
			(layer "B.Fab")
			(effects
				(font
					(size 1.27 1.27)
				)
				(justify mirror)
			)
		)
		(duplicate_pad_numbers_are_jumpers no)
		(fp_poly
			(pts
				(xy 0.4953 -0.2032) (xy -0.4953 -0.2032) (xy -0.4953 1.6002) (xy 0.4953 1.6002)
			)
			(stroke
				(width 0)
				(type default)
			)
			(fill no)
			(layer "B.CrtYd")
		)
		(fp_line
			(start 0.4953 1.6002)
			(end 0.4953 -0.2032)
			(stroke
				(width 0.1)
				(type default)
			)
			(layer "B.Fab")
		)
		(fp_line
			(start 0.4953 -0.2032)
			(end -0.4953 -0.2032)
			(stroke
				(width 0.1)
				(type default)
			)
			(layer "B.Fab")
		)
		(fp_line
			(start -0.4953 1.6002)
			(end 0.4953 1.6002)
			(stroke
				(width 0.1)
				(type default)
			)
			(layer "B.Fab")
		)
		(fp_line
			(start -0.4953 -0.2032)
			(end -0.4953 1.6002)
			(stroke
				(width 0.1)
				(type default)
			)
			(layer "B.Fab")
		)
		(pad "1" smd rect
			(at 0 0)
			(size 0.762 0.889)
			(layers "B.Cu" "B.Mask" "B.Paste")
			(net "P1V5_LAN")
		)
		(pad "2" smd rect
			(at 0 1.397)
			(size 0.762 0.889)
			(layers "B.Cu" "B.Mask" "B.Paste")
			(net "P1V5_LAN_I210")
		)
		(zone
			(layer "B.Cu")
			(hatch none 0.5)
			(connect_pads
				(clearance 0)
			)
			(min_thickness 0.25)
			(keepout
				(tracks not_allowed)
				(vias allowed)
				(pads allowed)
				(copperpour not_allowed)
				(footprints allowed)
			)
			(placement
				(enabled no)
				(sheetname "")
			)
			(fill
				(thermal_gap 0.5)
				(thermal_bridge_width 0.5)
				(island_removal_mode 0)
			)
			(polygon
				(pts
					(xy 482.5746 -39.3954) (xy 482.5746 -38.8874) (xy 483.3366 -38.8874) (xy 483.3366 -39.3954)
				)
			)
		)
		(zone
			(layer "B.Cu")
			(hatch none 0.5)
			(connect_pads
				(clearance 0)
			)
			(min_thickness 0.25)
			(keepout
				(tracks allowed)
				(vias not_allowed)
				(pads allowed)
				(copperpour not_allowed)
				(footprints allowed)
			)
			(placement
				(enabled no)
				(sheetname "")
			)
			(fill
				(thermal_gap 0.5)
				(thermal_bridge_width 0.5)
				(island_removal_mode 0)
			)
			(polygon
				(pts
					(xy 483.3366 -39.3954) (xy 483.3366 -38.8874) (xy 482.5746 -38.8874) (xy 482.5746 -39.3954)
				)
			)
		)
	)
)
